# S9S_MB_2U (Grand Teton) — schematic netlist excerpt (pin names and nets, part order shuffled) for the footprints in the layout excerpt that follows; sources: Cadence DE-HDL packaged netlist, KiCad conversion of 03242023_DA0F0TMBIJ0_F0T_Motherboard_J_brd_V01_OCP.brd

PC509  Q_CAP  100NF 50V 10% X7R  pkg C0402  page 287 : A = SW_PVCCIN_CPU1_BOOT6_R ; B = SW_PVCCIN_CPU1_BOOTR6
R329  Q_RES  0 EMPTY  pkg 1206LF  page 80 : A = PVCCINFAON_CPU1 ; B = PVNN_TERM_CPU1
R1366  Q_RES  100 1% CHIP  pkg 0402LF  page 239 : A = JTAG_DBP_TDO ; B = JTAG_DBP_FB_TDO

(kicad_pcb
	(version 20260206)
	(generator "pcbnew")
	(generator_version "10.0")
	(general
		(thickness 1.6)
		(legacy_teardrops no)
	)
	(paper "A4")
	(title_block
		(title "03242023_DA0F0TMBIJ0_F0T_Motherboard_J_brd_V01_OCP.brd")
		(comment 1 "Grand Teton / footprints 2211-2213 of 6105")
	)
	(layers
		(0 "F.Cu" signal "TOP")
		(4 "In1.Cu" signal "GND")
		(6 "In2.Cu" signal "IN1")
		(8 "In3.Cu" signal "GND1")
		(10 "In4.Cu" signal "IN2")
		(12 "In5.Cu" signal "GND2")
		(14 "In6.Cu" signal "IN3")
		(16 "In7.Cu" signal "GND3")
		(18 "In8.Cu" signal "VCC")
		(20 "In9.Cu" signal "VCC1")
		(22 "In10.Cu" signal "GND4")
		(24 "In11.Cu" signal "IN4")
		(26 "In12.Cu" signal "GND5")
		(28 "In13.Cu" signal "IN5")
		(30 "In14.Cu" signal "GND6")
		(32 "In15.Cu" signal "IN6")
		(34 "In16.Cu" signal "GND7")
		(2 "B.Cu" signal "BOTTOM")
		(9 "F.Adhes" user "F.Adhesive")
		(11 "B.Adhes" user "B.Adhesive")
		(13 "F.Paste" user "Package Geometry/Pastemask Top")
		(15 "B.Paste" user "Package Geometry/Pastemask Bottom")
		(5 "F.SilkS" user "Ref Des/Silkscreen Top")
		(7 "B.SilkS" user "Ref Des/Silkscreen Bottom")
		(1 "F.Mask" user "Board Geometry/Soldermask Top")
		(3 "B.Mask" user "Board Geometry/Soldermask Bottom")
		(17 "Dwgs.User" user "User.Drawings")
		(19 "Cmts.User" user "User.Comments")
		(21 "Eco1.User" user "User.Eco1")
		(23 "Eco2.User" user "User.Eco2")
		(25 "Edge.Cuts" user "Board Geometry/Outline")
		(27 "Margin" user)
		(31 "F.CrtYd" user "Package Geometry/Place Bound Top")
		(29 "B.CrtYd" user "Package Geometry/Place Bound Bottom")
		(35 "F.Fab" user "Ref Des/Assembly Top")
		(33 "B.Fab" user "Ref Des/Assembly Bottom")
	)
	(footprint ""
		(layer "F.Cu")
		(at 90.623136 -341.729822 -90)
		(property "Reference" "PC509"
			(at 0 0 270)
			(layer "F.SilkS")
			(hide yes)
			(effects
				(font
					(size 1.27 1.27)
				)
			)
		)
		(property "Value" ""
			(at 0 0 270)
			(layer "F.Fab")
			(effects
				(font
					(size 1.27 1.27)
				)
			)
		)
		(duplicate_pad_numbers_are_jumpers no)
		(fp_line
			(start -0.7874 0.4064)
			(end -0.7874 -0.4064)
			(stroke
				(width 0.1524)
				(type default)
			)
			(layer "F.SilkS")
		)
		(fp_line
			(start 0.7874 0.4064)
			(end -0.7874 0.4064)
			(stroke
				(width 0.1524)
				(type default)
			)
			(layer "F.SilkS")
		)
		(fp_line
			(start -0.7874 -0.4064)
			(end 0.7874 -0.4064)
			(stroke
				(width 0.1524)
				(type default)
			)
			(layer "F.SilkS")
		)
		(fp_line
			(start 0.7874 -0.4064)
			(end 0.7874 0.4064)
			(stroke
				(width 0.1524)
				(type default)
			)
			(layer "F.SilkS")
		)
		(fp_line
			(start -0.67945 0.3048)
			(end -0.67945 -0.305054)
			(stroke
				(width 0.1)
				(type default)
			)
			(layer "F.Fab")
		)
		(fp_line
			(start -0.12065 0.3048)
			(end -0.67945 0.3048)
			(stroke
				(width 0.1)
				(type default)
			)
			(layer "F.Fab")
		)
		(fp_line
			(start 0.120396 0.3048)
			(end 0.120396 0.2794)
			(stroke
				(width 0.1)
				(type default)
			)
			(layer "F.Fab")
		)
		(fp_line
			(start 0.67945 0.3048)
			(end 0.120396 0.3048)
			(stroke
				(width 0.1)
				(type default)
			)
			(layer "F.Fab")
		)
		(fp_line
			(start -0.12065 0.2794)
			(end -0.12065 0.3048)
			(stroke
				(width 0.1)
				(type default)
			)
			(layer "F.Fab")
		)
		(fp_line
			(start 0.120396 0.2794)
			(end -0.12065 0.2794)
			(stroke
				(width 0.1)
				(type default)
			)
			(layer "F.Fab")
		)
		(fp_line
			(start -0.12065 -0.2794)
			(end 0.12065 -0.2794)
			(stroke
				(width 0.1)
				(type default)
			)
			(layer "F.Fab")
		)
		(fp_line
			(start 0.12065 -0.2794)
			(end 0.12065 -0.3048)
			(stroke
				(width 0.1)
				(type default)
			)
			(layer "F.Fab")
		)
		(fp_line
			(start 0.12065 -0.3048)
			(end 0.67945 -0.3048)
			(stroke
				(width 0.1)
				(type default)
			)
			(layer "F.Fab")
		)
		(fp_line
			(start 0.67945 -0.3048)
			(end 0.67945 0.3048)
			(stroke
				(width 0.1)
				(type default)
			)
			(layer "F.Fab")
		)
		(fp_line
			(start -0.67945 -0.305054)
			(end -0.12065 -0.305054)
			(stroke
				(width 0.1)
				(type default)
			)
			(layer "F.Fab")
		)
		(fp_line
			(start -0.12065 -0.305054)
			(end -0.12065 -0.2794)
			(stroke
				(width 0.1)
				(type default)
			)
			(layer "F.Fab")
		)
		(pad "1" smd circle
			(at -0.40005 0 270)
			(size 0 0)
			(layers "F.Cu" "F.Mask" "F.Paste")
			(net "SW_PVCCIN_CPU1_BOOT6_R")
		)
		(pad "2" smd circle
			(at 0.40005 0 270)
			(size 0 0)
			(layers "F.Cu" "F.Mask" "F.Paste")
			(net "SW_PVCCIN_CPU1_BOOTR6")
		)
	)
	(footprint ""
		(layer "F.Cu")
		(at 375.255536 -105.483152 -90)
		(property "Reference" "R1366"
			(at 0 0 270)
			(layer "F.SilkS")
			(hide yes)
			(effects
				(font
					(size 1.27 1.27)
				)
			)
		)
		(property "Value" ""
			(at 0 0 270)
			(layer "F.Fab")
			(effects
				(font
					(size 1.27 1.27)
				)
			)
		)
		(duplicate_pad_numbers_are_jumpers no)
		(fp_line
			(start -0.7874 0.4064)
			(end -0.7874 -0.4064)
			(stroke
				(width 0.1524)
				(type default)
			)
			(layer "F.SilkS")
		)
		(fp_line
			(start 0.7874 0.4064)
			(end -0.7874 0.4064)
			(stroke
				(width 0.1524)
				(type default)
			)
			(layer "F.SilkS")
		)
		(fp_line
			(start -0.7874 -0.4064)
			(end 0.7874 -0.4064)
			(stroke
				(width 0.1524)
				(type default)
			)
			(layer "F.SilkS")
		)
		(fp_line
			(start 0.7874 -0.4064)
			(end 0.7874 0.4064)
			(stroke
				(width 0.1524)
				(type default)
			)
			(layer "F.SilkS")
		)
		(fp_line
			(start -0.67945 0.3048)
			(end -0.67945 -0.305054)
			(stroke
				(width 0.1)
				(type default)
			)
			(layer "F.Fab")
		)
		(fp_line
			(start -0.12065 0.3048)
			(end -0.67945 0.3048)
			(stroke
				(width 0.1)
				(type default)
			)
			(layer "F.Fab")
		)
		(fp_line
			(start 0.120396 0.3048)
			(end 0.120396 0.2794)
			(stroke
				(width 0.1)
				(type default)
			)
			(layer "F.Fab")
		)
		(fp_line
			(start 0.67945 0.3048)
			(end 0.120396 0.3048)
			(stroke
				(width 0.1)
				(type default)
			)
			(layer "F.Fab")
		)
		(fp_line
			(start -0.12065 0.2794)
			(end -0.12065 0.3048)
			(stroke
				(width 0.1)
				(type default)
			)
			(layer "F.Fab")
		)
		(fp_line
			(start 0.120396 0.2794)
			(end -0.12065 0.2794)
			(stroke
				(width 0.1)
				(type default)
			)
			(layer "F.Fab")
		)
		(fp_line
			(start -0.12065 -0.2794)
			(end 0.12065 -0.2794)
			(stroke
				(width 0.1)
				(type default)
			)
			(layer "F.Fab")
		)
		(fp_line
			(start 0.12065 -0.2794)
			(end 0.12065 -0.3048)
			(stroke
				(width 0.1)
				(type default)
			)
			(layer "F.Fab")
		)
		(fp_line
			(start 0.12065 -0.3048)
			(end 0.67945 -0.3048)
			(stroke
				(width 0.1)
				(type default)
			)
			(layer "F.Fab")
		)
		(fp_line
			(start 0.67945 -0.3048)
			(end 0.67945 0.3048)
			(stroke
				(width 0.1)
				(type default)
			)
			(layer "F.Fab")
		)
		(fp_line
			(start -0.67945 -0.305054)
			(end -0.12065 -0.305054)
			(stroke
				(width 0.1)
				(type default)
			)
			(layer "F.Fab")
		)
		(fp_line
			(start -0.12065 -0.305054)
			(end -0.12065 -0.2794)
			(stroke
				(width 0.1)
				(type default)
			)
			(layer "F.Fab")
		)
		(pad "1" smd circle
			(at -0.40005 0 270)
			(size 0 0)
			(layers "F.Cu" "F.Mask" "F.Paste")
			(net "JTAG_DBP_TDO")
		)
		(pad "2" smd circle
			(at 0.40005 0 270)
			(size 0 0)
			(layers "F.Cu" "F.Mask" "F.Paste")
			(net "JTAG_DBP_FB_TDO")
		)
	)
	(footprint ""
		(layer "F.Cu")
		(at 75.25893 -158.541974)
		(property "Reference" "R329"
			(at 0 0 0)
			(layer "F.SilkS")
			(hide yes)
			(effects
				(font
					(size 1.27 1.27)
				)
			)
		)
		(property "Value" ""
			(at 0 0 0)
			(layer "F.Fab")
			(effects
				(font
					(size 1.27 1.27)
				)
			)
		)
		(duplicate_pad_numbers_are_jumpers no)
		(fp_line
			(start -2.044192 -0.94361)
			(end -2.044192 0.898398)
			(stroke
				(width 0.1524)
				(type default)
			)
			(layer "F.SilkS")
		)
		(fp_line
			(start -2.044192 0.94361)
			(end 2.044192 0.94361)
			(stroke
				(width 0.1524)
				(type default)
			)
			(layer "F.SilkS")
		)
		(fp_line
			(start 2.044192 -0.94361)
			(end -2.044192 -0.94361)
			(stroke
				(width 0.1524)
				(type default)
			)
			(layer "F.SilkS")
		)
		(fp_line
			(start 2.044192 0.94361)
			(end 2.044192 -0.94361)
			(stroke
				(width 0.1524)
				(type default)
			)
			(layer "F.SilkS")
		)
		(fp_line
			(start -1.625092 -0.87503)
			(end -1.625092 0.87503)
			(stroke
				(width 0.1)
				(type default)
			)
			(layer "F.Fab")
		)
		(fp_line
			(start -1.625092 0.87503)
			(end 1.625092 0.87503)
			(stroke
				(width 0.1)
				(type default)
			)
			(layer "F.Fab")
		)
		(fp_line
			(start 1.625092 -0.87503)
			(end -1.625092 -0.87503)
			(stroke
				(width 0.1)
				(type default)
			)
			(layer "F.Fab")
		)
		(fp_line
			(start 1.625092 0.87503)
			(end 1.625092 -0.87503)
			(stroke
				(width 0.1)
				(type default)
			)
			(layer "F.Fab")
		)
		(pad "1" smd rect
			(at -1.450086 0)
			(size 0.9144 1.6002)
			(layers "F.Cu" "F.Mask" "F.Paste")
			(net "PVCCINFAON_CPU1")
		)
		(pad "2" smd rect
			(at 1.450086 0)
			(size 0.9144 1.6002)
			(layers "F.Cu" "F.Mask" "F.Paste")
			(net "PVNN_TERM_CPU1")
		)
	)
)
